# T6G (Grand Teton) — schematic netlist excerpt (pin names and nets, part order shuffled) for the footprints in the layout excerpt that follows; sources: Cadence DE-HDL packaged netlist, KiCad conversion of 04192023_DAF0TMB3IC0_F0TG_MB_C_brd_V02_OCP.brd

J99  SCONN288_DDR506112002KQ  IO  pkg DDR288S_1-1VXC  page 108
  VIN_BULK0  = P12V_MEM_CPU1
  RFU0  = NC
  VIN_MGMT  = P3V3_AUX
  HSCL  = I3C_SPD_DDRK_CPU1_SCL
  HSDA  = I3C_SPD_DDRK_CPU1_SDA
  VSS0  = GND
  DQ0_A  = M_K_CPU1_SA_DQ<0>
  VSS1  = GND
  DQ1_A  = M_K_CPU1_SA_DQ<1>
  VSS2  = GND
  DQS0_A_T  = M_K_CPU1_SA_DQS_DP<0>
  DQS0_A_C  = M_K_CPU1_SA_DQS_DN<0>
  VSS3  = GND
  DQ4_A  = M_K_CPU1_SA_DQ<4>
  VSS4  = GND
  DQ5_A  = M_K_CPU1_SA_DQ<5>
  VSS5  = GND
  DQ8_A  = M_K_CPU1_SA_DQ<8>
  VSS6  = GND
  DQ9_A  = M_K_CPU1_SA_DQ<9>
  VSS7  = GND
  DQS1_A_T  = M_K_CPU1_SA_DQS_DP<1>
  DQS1_A_C  = M_K_CPU1_SA_DQS_DN<1>
  VSS8  = GND
  DQ12_A  = M_K_CPU1_SA_DQ<12>
  VSS9  = GND
  DQ13_A  = M_K_CPU1_SA_DQ<13>
  VSS10  = GND
  DQ16_A  = M_K_CPU1_SA_DQ<16>
  VSS11  = GND
  DQ17_A  = M_K_CPU1_SA_DQ<17>
  VSS12  = GND
  DQS2_A_T  = M_K_CPU1_SA_DQS_DP<2>
  DQS2_A_C  = M_K_CPU1_SA_DQS_DN<2>
  VSS13  = GND
  DQ20_A  = M_K_CPU1_SA_DQ<20>
  VSS14  = GND
  DQ21_A  = M_K_CPU1_SA_DQ<21>
  VSS15  = GND
  DQ24_A  = M_K_CPU1_SA_DQ<24>
  VSS16  = GND
  DQ25_A  = M_K_CPU1_SA_DQ<25>
  VSS17  = GND
  DQS3_A_T  = M_K_CPU1_SA_DQS_DP<3>
  DQS3_A_C  = M_K_CPU1_SA_DQS_DN<3>
  VSS18  = GND
  DQ28_A  = M_K_CPU1_SA_DQ<28>
  VSS19  = GND
  DQ29_A  = M_K_CPU1_SA_DQ<29>
  VSS20  = GND
  CB0_A  = M_K_CPU1_SA_CB<0>
  VSS21  = GND
  CB1_A  = M_K_CPU1_SA_CB<1>
  VSS22  = GND
  DQS4_A_T  = M_K_CPU1_SA_DQS_DP<4>
  DQS4_A_C  = M_K_CPU1_SA_DQS_DN<4>
  VSS23  = GND
  CB4_A  = M_K_CPU1_SA_CB<4>
  VSS24  = GND
  CB5_A  = M_K_CPU1_SA_CB<5>
  VSS25  = GND
  ALERT_N  = M_K_CPU1_ALERT_N
  VSS26  = GND
  CS0_A_N  = M_K_CPU1_SA_CS_N<0>
  VSS27  = GND
  CA0_A  = M_K_CPU1_SA_CA<0>
  VSS28  = GND
  CA2_A  = M_K_CPU1_SA_CA<2>
  VSS29  = GND
  CA4_A  = M_K_CPU1_SA_CA<4>
  VSS30  = GND
  CA6_A  = M_K_CPU1_SA_CA<6>
  VSS31  = GND
  PAR_A  = M_K_CPU1_SA_PAR
  VSS32  = GND
  CA0_B  = M_K_CPU1_SB_CA<0>
  VSS33  = GND
  CA2_B  = M_K_CPU1_SB_CA<2>
  VSS34  = GND
  CA4_B  = M_K_CPU1_SB_CA<4>
  VSS35  = GND
  CA6_B  = M_K_CPU1_SB_CA<6>
  VSS36  = GND
  CS0_B_N  = M_K_CPU1_SB_CS_N<0>
  VSS37  = GND
  \lbd||rsp_a_n\  = M_K_CPU1_SA_RSP<0>
  \lbs||rsp_b_n\  = M_K_CPU1_SB_RSP<0>
  VSS38  = GND
  CB4_B  = M_K_CPU1_SB_CB<4>
  VSS39  = GND
  CB5_B  = M_K_CPU1_SB_CB<5>
  VSS40  = GND
  \dqs9_b_t||tdqs9_b_t||dbi4_b_n\  = M_K_CPU1_SB_DQS_DP<9>
  \dqs9_b_c||tdqs9_b_c\  = M_K_CPU1_SB_DQS_DN<9>
  VSS41  = GND
  CB0_B  = M_K_CPU1_SB_CB<0>
  VSS42  = GND
  CB1_B  = M_K_CPU1_SB_CB<1>
  VSS43  = GND
  DQ0_B  = M_K_CPU1_SB_DQ<0>
  VSS44  = GND
  DQ1_B  = M_K_CPU1_SB_DQ<1>
  VSS45  = GND
  DQS0_B_T  = M_K_CPU1_SB_DQS_DP<0>
  DQS0_B_C  = M_K_CPU1_SB_DQS_DN<0>
  VSS46  = GND
  DQ4_B  = M_K_CPU1_SB_DQ<4>
  VSS47  = GND
  DQ5_B  = M_K_CPU1_SB_DQ<5>
  VSS48  = GND
  DQ8_B  = M_K_CPU1_SB_DQ<8>
  VSS49  = GND
  DQ9_B  = M_K_CPU1_SB_DQ<9>
  VSS50  = GND
  DQS1_B_T  = M_K_CPU1_SB_DQS_DP<1>
  DQS1_B_C  = M_K_CPU1_SB_DQS_DN<1>
  VSS51  = GND
  DQ12_B  = M_K_CPU1_SB_DQ<12>
  VSS52  = GND
  DQ13_B  = M_K_CPU1_SB_DQ<13>
  VSS53  = GND
  DQ16_B  = M_K_CPU1_SB_DQ<16>
  VSS54  = GND
  DQ17_B  = M_K_CPU1_SB_DQ<17>
  VSS55  = GND
  DQS2_B_T  = M_K_CPU1_SB_DQS_DP<2>
  DQS2_B_C  = M_K_CPU1_SB_DQS_DN<2>
  VSS56  = GND
  DQ20_B  = M_K_CPU1_SB_DQ<20>
  VSS57  = GND
  DQ21_B  = M_K_CPU1_SB_DQ<21>
  VSS58  = GND
  DQ24_B  = M_K_CPU1_SB_DQ<24>
  VSS59  = GND
  DQ25_B  = M_K_CPU1_SB_DQ<25>
  VSS60  = GND
  DQS3_B_T  = M_K_CPU1_SB_DQS_DP<3>
  DQS3_B_C  = M_K_CPU1_SB_DQS_DN<3>
  VSS61  = GND
  DQ28_B  = M_K_CPU1_SB_DQ<28>
  VSS62  = GND
  DQ29_B  = M_K_CPU1_SB_DQ<29>
  VSS63  = GND
  RFU1  = NC
  VIN_BULK1  = P12V_MEM_CPU1
  VIN_BULK2  = P12V_MEM_CPU1
  \pwr_good||fail_n\  = PWRGD_CHK_CPU1_DIMM
  HAS  = PD_CHK_CPU1_DIMM_SAA
  RFU2  = NC
  RFU3  = NC
  VSS64  = GND
  DQ2_A  = M_K_CPU1_SA_DQ<2>
  VSS65  = GND
  DQ3_A  = M_K_CPU1_SA_DQ<3>
  VSS66  = GND
  \dqs5_a_c||tdqs5_a_c||dqs5_a_t||tdqs5_a_t\  = M_K_CPU1_SA_DQS_DN<5>
  \dqs5_a_t||tdqs5_a_t\  = M_K_CPU1_SA_DQS_DP<5>
  VSS67  = GND
  DQ6_A  = M_K_CPU1_SA_DQ<6>
  VSS68  = GND
  DQ7_A  = M_K_CPU1_SA_DQ<7>
  VSS69  = GND
  DQ10_A  = M_K_CPU1_SA_DQ<10>
  VSS70  = GND
  DQ11_A  = M_K_CPU1_SA_DQ<11>
  VSS71  = GND
  \dqs6_a_c||tdqs6_a_c||dqs6_a_t||tdqs6_a_t\  = M_K_CPU1_SA_DQS_DN<6>
  \dqs6_a_t||tdqs6_a_t\  = M_K_CPU1_SA_DQS_DP<6>
  VSS72  = GND
  DQ14_A  = M_K_CPU1_SA_DQ<14>
  VSS73  = GND
  DQ15_A  = M_K_CPU1_SA_DQ<15>
  VSS74  = GND
  DQ18_A  = M_K_CPU1_SA_DQ<18>
  VSS75  = GND
  DQ19_A  = M_K_CPU1_SA_DQ<19>
  VSS76  = GND
  \dqs7_a_c||tdqs7_a_c\  = M_K_CPU1_SA_DQS_DN<7>
  \dqs7_a_t||tdqs7_a_t\  = M_K_CPU1_SA_DQS_DP<7>
  VSS77  = GND
  DQ22_A  = M_K_CPU1_SA_DQ<22>
  VSS78  = GND
  DQ23_A  = M_K_CPU1_SA_DQ<23>
  VSS79  = GND
  DQ26_A  = M_K_CPU1_SA_DQ<26>
  VSS80  = GND
  DQ27_A  = M_K_CPU1_SA_DQ<27>
  VSS81  = GND
  \dqs8_a_c||tdqs8_a_c\  = M_K_CPU1_SA_DQS_DN<8>
  \dqs8_a_t||tdqs8_a_t\  = M_K_CPU1_SA_DQS_DP<8>
  VSS82  = GND
  DQ30_A  = M_K_CPU1_SA_DQ<30>
  VSS83  = GND
  DQ31_A  = M_K_CPU1_SA_DQ<31>
  VSS84  = GND
  CB2_A  = M_K_CPU1_SA_CB<2>
  VSS85  = GND
  CB3_A  = M_K_CPU1_SA_CB<3>
  VSS86  = GND
  \dqs9_a_c||tdqs9_a_c\  = M_K_CPU1_SA_DQS_DN<9>
  \dqs9_a_t||tdqs9_a_t\  = M_K_CPU1_SA_DQS_DP<9>
  VSS87  = GND
  CB6_A  = M_K_CPU1_SA_CB<6>
  VSS88  = GND
  CB7_A  = M_K_CPU1_SA_CB<7>
  VSS89  = GND
  RESET_N  = M_K_CPU1_RESET_N
  VSS90  = GND
  CS1_A_N  = M_K_CPU1_SA_CS_N<1>
  VSS91  = GND
  CA1_A  = M_K_CPU1_SA_CA<1>
  VSS92  = GND
  CA3_A  = M_K_CPU1_SA_CA<3>
  VSS93  = GND
  CA5_A  = M_K_CPU1_SA_CA<5>
  VSS94  = GND
  CK_T  = M_K_CPU1_CLK_DP<0>
  CK_C  = M_K_CPU1_CLK_DN<0>
  VSS95  = GND
  RFU4  = NC
  CA1_B  = M_K_CPU1_SB_CA<1>
  VSS96  = GND
  CA3_B  = M_K_CPU1_SB_CA<3>
  VSS97  = GND
  CA5_B  = M_K_CPU1_SB_CA<5>
  VSS98  = GND
  PAR_B  = M_K_CPU1_SB_PAR
  VSS99  = GND
  CS1_B_N  = M_K_CPU1_SB_CS_N<1>
  VSS100  = GND
  RFU5  = NC
  RFU6  = NC
  VSS101  = GND
  CB6_B  = M_K_CPU1_SB_CB<6>
  VSS102  = GND
  CB7_B  = M_K_CPU1_SB_CB<7>
  VSS103  = GND
  DQS4_B_C  = M_K_CPU1_SB_DQS_DN<4>
  DQS4_B_T  = M_K_CPU1_SB_DQS_DP<4>
  VSS104  = GND
  CB2_B  = M_K_CPU1_SB_CB<2>
  VSS105  = GND
  CB3_B  = M_K_CPU1_SB_CB<3>
  VSS106  = GND
  DQ2_B  = M_K_CPU1_SB_DQ<2>
  VSS107  = GND
  DQ3_B  = M_K_CPU1_SB_DQ<3>
  VSS108  = GND
  \dqs5_b_c||tdqs5_b_c\  = M_K_CPU1_SB_DQS_DN<5>
  \dqs5_b_t||tdqs5_b_t\  = M_K_CPU1_SB_DQS_DP<5>
  VSS109  = GND
  DQ6_B  = M_K_CPU1_SB_DQ<6>
  VSS110  = GND
  DQ7_B  = M_K_CPU1_SB_DQ<7>
  VSS111  = GND
  DQ10_B  = M_K_CPU1_SB_DQ<10>
  VSS112  = GND
  DQ11_B  = M_K_CPU1_SB_DQ<11>
  VSS113  = GND
  \dqs6_b_c||tdqs6_b_c\  = M_K_CPU1_SB_DQS_DN<6>
  \dqs6_b_t||tdqs6_b_t\  = M_K_CPU1_SB_DQS_DP<6>
  VSS114  = GND
  DQ14_B  = M_K_CPU1_SB_DQ<14>
  VSS115  = GND
  DQ15_B  = M_K_CPU1_SB_DQ<15>
  VSS116  = GND
  DQ18_B  = M_K_CPU1_SB_DQ<18>
  VSS117  = GND
  DQ19_B  = M_K_CPU1_SB_DQ<19>
  VSS118  = GND
  \dqs7_b_c||tdqs7_b_c\  = M_K_CPU1_SB_DQS_DN<7>
  \dqs7_b_t||tdqs7_b_t\  = M_K_CPU1_SB_DQS_DP<7>
  VSS119  = GND
  DQ22_B  = M_K_CPU1_SB_DQ<22>
  VSS120  = GND
  DQ23_B  = M_K_CPU1_SB_DQ<23>
  VSS121  = GND
  DQ26_B  = M_K_CPU1_SB_DQ<26>
  VSS122  = GND
  DQ27_B  = M_K_CPU1_SB_DQ<27>
  VSS123  = GND
  \dqs8_b_c||tdqs8_b_c\  = M_K_CPU1_SB_DQS_DN<8>
  \dqs8_b_t||tdqs8_b_t\  = M_K_CPU1_SB_DQS_DP<8>
  VSS124  = GND
  DQ30_B  = M_K_CPU1_SB_DQ<30>
  VSS125  = GND
  DQ31_B  = M_K_CPU1_SB_DQ<31>
  VSS126  = GND
  G1  = GND
  G2  = GND
  G3  = GND

(kicad_pcb
	(version 20260206)
	(generator "pcbnew")
	(generator_version "10.0")
	(general
		(thickness 1.6)
		(legacy_teardrops no)
	)
	(paper "A4")
	(title_block
		(title "04192023_DAF0TMB3IC0_F0TG_MB_C_brd_V02_OCP.brd")
		(comment 1 "Grand Teton / footprint 4555 of 8354 (J99), pads 1-46 of 291")
	)
	(layers
		(0 "F.Cu" signal "TOP")
		(4 "In1.Cu" signal "GND")
		(6 "In2.Cu" signal "IN1")
		(8 "In3.Cu" signal "GND1")
		(10 "In4.Cu" signal "IN2")
		(12 "In5.Cu" signal "GND2")
		(14 "In6.Cu" signal "IN3")
		(16 "In7.Cu" signal "GND3")
		(18 "In8.Cu" signal "VCC")
		(20 "In9.Cu" signal "VCC1")
		(22 "In10.Cu" signal "GND4")
		(24 "In11.Cu" signal "IN4")
		(26 "In12.Cu" signal "GND5")
		(28 "In13.Cu" signal "IN5")
		(30 "In14.Cu" signal "GND6")
		(32 "In15.Cu" signal "IN6")
		(34 "In16.Cu" signal "GND7")
		(2 "B.Cu" signal "BOTTOM")
		(9 "F.Adhes" user "F.Adhesive")
		(11 "B.Adhes" user "B.Adhesive")
		(13 "F.Paste" user "Package Geometry/Pastemask Top")
		(15 "B.Paste" user "Package Geometry/Pastemask Bottom")
		(5 "F.SilkS" user "Ref Des/Silkscreen Top")
		(7 "B.SilkS" user "Ref Des/Silkscreen Bottom")
		(1 "F.Mask" user "Board Geometry/Soldermask Top")
		(3 "B.Mask" user "Board Geometry/Soldermask Bottom")
		(17 "Dwgs.User" user "User.Drawings")
		(19 "Cmts.User" user "User.Comments")
		(21 "Eco1.User" user "User.Eco1")
		(23 "Eco2.User" user "User.Eco2")
		(25 "Edge.Cuts" user "Board Geometry/Outline")
		(27 "Margin" user)
		(31 "F.CrtYd" user "Package Geometry/Place Bound Top")
		(29 "B.CrtYd" user "Package Geometry/Place Bound Bottom")
		(35 "F.Fab" user "Ref Des/Assembly Top")
		(33 "B.Fab" user "Ref Des/Assembly Bottom")
	)
	(footprint ""
		(layer "F.Cu")
		(at 196.654166 -255.560322 180)
		(property "Reference" "J99"
			(at -0.4318 -81.730088 0)
			(unlocked yes)
			(layer "F.SilkS")
			(effects
				(font
					(size 0.7874 0.5842)
					(thickness 0.1524)
				)
			)
		)
		(property "Value" ""
			(at 0 0 180)
			(layer "F.Fab")
			(effects
				(font
					(size 1.27 1.27)
				)
			)
		)
		(duplicate_pad_numbers_are_jumpers no)
		(pad "1" smd rect
			(at -2.050034 -63.324994 90)
			(size 0.519938 1.4986)
			(layers "F.Cu" "F.Mask" "F.Paste")
			(net "P12V_MEM_CPU1")
		)
		(pad "2" smd rect
			(at -2.050034 -62.47511 90)
			(size 0.519938 1.4986)
			(layers "F.Cu" "F.Mask" "F.Paste")
			(net "Net_2396")
		)
		(pad "3" smd rect
			(at -2.050034 -61.624972 90)
			(size 0.519938 1.4986)
			(layers "F.Cu" "F.Mask" "F.Paste")
			(net "P3V3_AUX")
		)
		(pad "4" smd rect
			(at -2.050034 -60.775088 90)
			(size 0.519938 1.4986)
			(layers "F.Cu" "F.Mask" "F.Paste")
			(net "I3C_SPD_DDRK_CPU1_SCL")
		)
		(pad "5" smd rect
			(at -2.050034 -59.92495 90)
			(size 0.519938 1.4986)
			(layers "F.Cu" "F.Mask" "F.Paste")
			(net "I3C_SPD_DDRK_CPU1_SDA")
		)
		(pad "6" smd rect
			(at -2.050034 -59.075066 90)
			(size 0.519938 1.4986)
			(layers "F.Cu" "F.Mask" "F.Paste")
			(net "GND")
		)
		(pad "7" smd rect
			(at -2.050034 -58.224928 90)
			(size 0.519938 1.4986)
			(layers "F.Cu" "F.Mask" "F.Paste")
			(net "M_K_CPU1_SA_DQ<0>")
		)
		(pad "8" smd rect
			(at -2.050034 -57.375044 90)
			(size 0.519938 1.4986)
			(layers "F.Cu" "F.Mask" "F.Paste")
			(net "GND")
		)
		(pad "9" smd rect
			(at -2.050034 -56.524906 90)
			(size 0.519938 1.4986)
			(layers "F.Cu" "F.Mask" "F.Paste")
			(net "M_K_CPU1_SA_DQ<1>")
		)
		(pad "10" smd rect
			(at -2.050034 -55.675022 90)
			(size 0.519938 1.4986)
			(layers "F.Cu" "F.Mask" "F.Paste")
			(net "GND")
		)
		(pad "11" smd rect
			(at -2.050034 -54.824884 90)
			(size 0.519938 1.4986)
			(layers "F.Cu" "F.Mask" "F.Paste")
			(net "M_K_CPU1_SA_DQS_DP<0>")
		)
		(pad "12" smd rect
			(at -2.050034 -53.975 90)
			(size 0.519938 1.4986)
			(layers "F.Cu" "F.Mask" "F.Paste")
			(net "M_K_CPU1_SA_DQS_DN<0>")
		)
		(pad "13" smd rect
			(at -2.050034 -53.125116 90)
			(size 0.519938 1.4986)
			(layers "F.Cu" "F.Mask" "F.Paste")
			(net "GND")
		)
		(pad "14" smd rect
			(at -2.050034 -52.274978 90)
			(size 0.519938 1.4986)
			(layers "F.Cu" "F.Mask" "F.Paste")
			(net "M_K_CPU1_SA_DQ<4>")
		)
		(pad "15" smd rect
			(at -2.050034 -51.425094 90)
			(size 0.519938 1.4986)
			(layers "F.Cu" "F.Mask" "F.Paste")
			(net "GND")
		)
		(pad "16" smd rect
			(at -2.050034 -50.574956 90)
			(size 0.519938 1.4986)
			(layers "F.Cu" "F.Mask" "F.Paste")
			(net "M_K_CPU1_SA_DQ<5>")
		)
		(pad "17" smd rect
			(at -2.050034 -49.725072 90)
			(size 0.519938 1.4986)
			(layers "F.Cu" "F.Mask" "F.Paste")
			(net "GND")
		)
		(pad "18" smd rect
			(at -2.050034 -48.874934 90)
			(size 0.519938 1.4986)
			(layers "F.Cu" "F.Mask" "F.Paste")
			(net "M_K_CPU1_SA_DQ<8>")
		)
		(pad "19" smd rect
			(at -2.050034 -48.02505 90)
			(size 0.519938 1.4986)
			(layers "F.Cu" "F.Mask" "F.Paste")
			(net "GND")
		)
		(pad "20" smd rect
			(at -2.050034 -47.174912 90)
			(size 0.519938 1.4986)
			(layers "F.Cu" "F.Mask" "F.Paste")
			(net "M_K_CPU1_SA_DQ<9>")
		)
		(pad "21" smd rect
			(at -2.050034 -46.325028 90)
			(size 0.519938 1.4986)
			(layers "F.Cu" "F.Mask" "F.Paste")
			(net "GND")
		)
		(pad "22" smd rect
			(at -2.050034 -45.47489 90)
			(size 0.519938 1.4986)
			(layers "F.Cu" "F.Mask" "F.Paste")
			(net "M_K_CPU1_SA_DQS_DP<1>")
		)
		(pad "23" smd rect
			(at -2.050034 -44.625006 90)
			(size 0.519938 1.4986)
			(layers "F.Cu" "F.Mask" "F.Paste")
			(net "M_K_CPU1_SA_DQS_DN<1>")
		)
		(pad "24" smd rect
			(at -2.050034 -43.775122 90)
			(size 0.519938 1.4986)
			(layers "F.Cu" "F.Mask" "F.Paste")
			(net "GND")
		)
		(pad "25" smd rect
			(at -2.050034 -42.924984 90)
			(size 0.519938 1.4986)
			(layers "F.Cu" "F.Mask" "F.Paste")
			(net "M_K_CPU1_SA_DQ<12>")
		)
		(pad "26" smd rect
			(at -2.050034 -42.0751 90)
			(size 0.519938 1.4986)
			(layers "F.Cu" "F.Mask" "F.Paste")
			(net "GND")
		)
		(pad "27" smd rect
			(at -2.050034 -41.224962 90)
			(size 0.519938 1.4986)
			(layers "F.Cu" "F.Mask" "F.Paste")
			(net "M_K_CPU1_SA_DQ<13>")
		)
		(pad "28" smd rect
			(at -2.050034 -40.375078 90)
			(size 0.519938 1.4986)
			(layers "F.Cu" "F.Mask" "F.Paste")
			(net "GND")
		)
		(pad "29" smd rect
			(at -2.050034 -39.52494 90)
			(size 0.519938 1.4986)
			(layers "F.Cu" "F.Mask" "F.Paste")
			(net "M_K_CPU1_SA_DQ<16>")
		)
		(pad "30" smd rect
			(at -2.050034 -38.675056 90)
			(size 0.519938 1.4986)
			(layers "F.Cu" "F.Mask" "F.Paste")
			(net "GND")
		)
		(pad "31" smd rect
			(at -2.050034 -37.824918 90)
			(size 0.519938 1.4986)
			(layers "F.Cu" "F.Mask" "F.Paste")
			(net "M_K_CPU1_SA_DQ<17>")
		)
		(pad "32" smd rect
			(at -2.050034 -36.975034 90)
			(size 0.519938 1.4986)
			(layers "F.Cu" "F.Mask" "F.Paste")
			(net "GND")
		)
		(pad "33" smd rect
			(at -2.050034 -36.124896 90)
			(size 0.519938 1.4986)
			(layers "F.Cu" "F.Mask" "F.Paste")
			(net "M_K_CPU1_SA_DQS_DP<2>")
		)
		(pad "34" smd rect
			(at -2.050034 -35.275012 90)
			(size 0.519938 1.4986)
			(layers "F.Cu" "F.Mask" "F.Paste")
			(net "M_K_CPU1_SA_DQS_DN<2>")
		)
		(pad "35" smd rect
			(at -2.050034 -34.425128 90)
			(size 0.519938 1.4986)
			(layers "F.Cu" "F.Mask" "F.Paste")
			(net "GND")
		)
		(pad "36" smd rect
			(at -2.050034 -33.57499 90)
			(size 0.519938 1.4986)
			(layers "F.Cu" "F.Mask" "F.Paste")
			(net "M_K_CPU1_SA_DQ<20>")
		)
		(pad "37" smd rect
			(at -2.050034 -32.725106 90)
			(size 0.519938 1.4986)
			(layers "F.Cu" "F.Mask" "F.Paste")
			(net "GND")
		)
		(pad "38" smd rect
			(at -2.050034 -31.874968 90)
			(size 0.519938 1.4986)
			(layers "F.Cu" "F.Mask" "F.Paste")
			(net "M_K_CPU1_SA_DQ<21>")
		)
		(pad "39" smd rect
			(at -2.050034 -31.025084 90)
			(size 0.519938 1.4986)
			(layers "F.Cu" "F.Mask" "F.Paste")
			(net "GND")
		)
		(pad "40" smd rect
			(at -2.050034 -30.174946 90)
			(size 0.519938 1.4986)
			(layers "F.Cu" "F.Mask" "F.Paste")
			(net "M_K_CPU1_SA_DQ<24>")
		)
		(pad "41" smd rect
			(at -2.050034 -29.325062 90)
			(size 0.519938 1.4986)
			(layers "F.Cu" "F.Mask" "F.Paste")
			(net "GND")
		)
		(pad "42" smd rect
			(at -2.050034 -28.474924 90)
			(size 0.519938 1.4986)
			(layers "F.Cu" "F.Mask" "F.Paste")
			(net "M_K_CPU1_SA_DQ<25>")
		)
		(pad "43" smd rect
			(at -2.050034 -27.62504 90)
			(size 0.519938 1.4986)
			(layers "F.Cu" "F.Mask" "F.Paste")
			(net "GND")
		)
		(pad "44" smd rect
			(at -2.050034 -26.774902 90)
			(size 0.519938 1.4986)
			(layers "F.Cu" "F.Mask" "F.Paste")
			(net "M_K_CPU1_SA_DQS_DP<3>")
		)
		(pad "45" smd rect
			(at -2.050034 -25.925018 90)
			(size 0.519938 1.4986)
			(layers "F.Cu" "F.Mask" "F.Paste")
			(net "M_K_CPU1_SA_DQS_DN<3>")
		)
		(pad "46" smd rect
			(at -2.050034 -25.07488 90)
			(size 0.519938 1.4986)
			(layers "F.Cu" "F.Mask" "F.Paste")
			(net "GND")
		)
	)
)
